# T6G (Grand Teton) — schematic netlist excerpt (pin names and nets, part order shuffled) for the footprints in the layout excerpt that follows; sources: Cadence DE-HDL packaged netlist, KiCad conversion of 04192023_DAF0TMB3IC0_F0TG_MB_C_brd_V02_OCP.brd

R324  Q_RES  0 5% EMPTY  pkg 0402LF  page 161 : A = SMB_CPU0_CPU1_APML_SCL_R2 ; B = SMB_CPU0_CPU1_APML_MUX1_SCL
C1005  Q_CAP  0.1UF 10V 10% X7S  pkg C0201  page 312 : A = P1V8_CPU0_RT3_1A ; B = GND
R388  Q_RES  2.2K 5% CHIP  pkg 0402LF  page 27 : A = P3V3_AUX ; B = CPU0_CORETYPE1

(kicad_pcb
	(version 20260206)
	(generator "pcbnew")
	(generator_version "10.0")
	(general
		(thickness 1.6)
		(legacy_teardrops no)
	)
	(paper "A4")
	(title_block
		(title "04192023_DAF0TMB3IC0_F0TG_MB_C_brd_V02_OCP.brd")
		(comment 1 "Grand Teton / footprints 6499-6501 of 8354")
	)
	(layers
		(0 "F.Cu" signal "TOP")
		(4 "In1.Cu" signal "GND")
		(6 "In2.Cu" signal "IN1")
		(8 "In3.Cu" signal "GND1")
		(10 "In4.Cu" signal "IN2")
		(12 "In5.Cu" signal "GND2")
		(14 "In6.Cu" signal "IN3")
		(16 "In7.Cu" signal "GND3")
		(18 "In8.Cu" signal "VCC")
		(20 "In9.Cu" signal "VCC1")
		(22 "In10.Cu" signal "GND4")
		(24 "In11.Cu" signal "IN4")
		(26 "In12.Cu" signal "GND5")
		(28 "In13.Cu" signal "IN5")
		(30 "In14.Cu" signal "GND6")
		(32 "In15.Cu" signal "IN6")
		(34 "In16.Cu" signal "GND7")
		(2 "B.Cu" signal "BOTTOM")
		(9 "F.Adhes" user "F.Adhesive")
		(11 "B.Adhes" user "B.Adhesive")
		(13 "F.Paste" user "Package Geometry/Pastemask Top")
		(15 "B.Paste" user "Package Geometry/Pastemask Bottom")
		(5 "F.SilkS" user "Ref Des/Silkscreen Top")
		(7 "B.SilkS" user "Ref Des/Silkscreen Bottom")
		(1 "F.Mask" user "Board Geometry/Soldermask Top")
		(3 "B.Mask" user "Board Geometry/Soldermask Bottom")
		(17 "Dwgs.User" user "User.Drawings")
		(19 "Cmts.User" user "User.Comments")
		(21 "Eco1.User" user "User.Eco1")
		(23 "Eco2.User" user "User.Eco2")
		(25 "Edge.Cuts" user "Board Geometry/Outline")
		(27 "Margin" user)
		(31 "F.CrtYd" user "Package Geometry/Place Bound Top")
		(29 "B.CrtYd" user "Package Geometry/Place Bound Bottom")
		(35 "F.Fab" user "Ref Des/Assembly Top")
		(33 "B.Fab" user "Ref Des/Assembly Bottom")
	)
	(footprint ""
		(layer "B.Cu")
		(at 231.775 -242.443 90)
		(property "Reference" "R324"
			(at 0 0 90)
			(layer "B.SilkS")
			(hide yes)
			(effects
				(font
					(size 1.27 1.27)
				)
				(justify mirror)
			)
		)
		(property "Value" ""
			(at 0 0 90)
			(layer "B.Fab")
			(effects
				(font
					(size 1.27 1.27)
				)
				(justify mirror)
			)
		)
		(duplicate_pad_numbers_are_jumpers no)
		(fp_line
			(start 0.7874 -0.4064)
			(end -0.7874 -0.4064)
			(stroke
				(width 0.1524)
				(type default)
			)
			(layer "B.SilkS")
		)
		(fp_line
			(start -0.7874 -0.4064)
			(end -0.7874 0.4064)
			(stroke
				(width 0.1524)
				(type default)
			)
			(layer "B.SilkS")
		)
		(fp_line
			(start 0.7874 0.4064)
			(end 0.7874 -0.4064)
			(stroke
				(width 0.1524)
				(type default)
			)
			(layer "B.SilkS")
		)
		(fp_line
			(start -0.7874 0.4064)
			(end 0.7874 0.4064)
			(stroke
				(width 0.1524)
				(type default)
			)
			(layer "B.SilkS")
		)
		(fp_line
			(start 0.67945 -0.305054)
			(end 0.12065 -0.305054)
			(stroke
				(width 0.1)
				(type default)
			)
			(layer "B.Fab")
		)
		(fp_line
			(start 0.12065 -0.305054)
			(end 0.12065 -0.2794)
			(stroke
				(width 0.1)
				(type default)
			)
			(layer "B.Fab")
		)
		(fp_line
			(start -0.12065 -0.3048)
			(end -0.67945 -0.3048)
			(stroke
				(width 0.1)
				(type default)
			)
			(layer "B.Fab")
		)
		(fp_line
			(start -0.67945 -0.3048)
			(end -0.67945 0.3048)
			(stroke
				(width 0.1)
				(type default)
			)
			(layer "B.Fab")
		)
		(fp_line
			(start 0.12065 -0.2794)
			(end -0.12065 -0.2794)
			(stroke
				(width 0.1)
				(type default)
			)
			(layer "B.Fab")
		)
		(fp_line
			(start -0.12065 -0.2794)
			(end -0.12065 -0.3048)
			(stroke
				(width 0.1)
				(type default)
			)
			(layer "B.Fab")
		)
		(fp_line
			(start 0.12065 0.2794)
			(end 0.12065 0.3048)
			(stroke
				(width 0.1)
				(type default)
			)
			(layer "B.Fab")
		)
		(fp_line
			(start -0.120396 0.2794)
			(end 0.12065 0.2794)
			(stroke
				(width 0.1)
				(type default)
			)
			(layer "B.Fab")
		)
		(fp_line
			(start 0.67945 0.3048)
			(end 0.67945 -0.305054)
			(stroke
				(width 0.1)
				(type default)
			)
			(layer "B.Fab")
		)
		(fp_line
			(start 0.12065 0.3048)
			(end 0.67945 0.3048)
			(stroke
				(width 0.1)
				(type default)
			)
			(layer "B.Fab")
		)
		(fp_line
			(start -0.120396 0.3048)
			(end -0.120396 0.2794)
			(stroke
				(width 0.1)
				(type default)
			)
			(layer "B.Fab")
		)
		(fp_line
			(start -0.67945 0.3048)
			(end -0.120396 0.3048)
			(stroke
				(width 0.1)
				(type default)
			)
			(layer "B.Fab")
		)
		(pad "1" smd rect
			(at 0.40005 0 90)
			(size 0.4572 0.508)
			(layers "B.Cu" "B.Mask" "B.Paste")
			(net "SMB_CPU0_CPU1_APML_SCL_R2")
		)
		(pad "2" smd rect
			(at -0.40005 0 90)
			(size 0.4572 0.508)
			(layers "B.Cu" "B.Mask" "B.Paste")
			(net "SMB_CPU0_CPU1_APML_MUX1_SCL")
		)
	)
	(footprint ""
		(layer "B.Cu")
		(at 380.218442 -396.393162 -90)
		(property "Reference" "C1005"
			(at 0 0 90)
			(layer "B.SilkS")
			(hide yes)
			(effects
				(font
					(size 1.27 1.27)
				)
				(justify mirror)
			)
		)
		(property "Value" ""
			(at 0 0 90)
			(layer "B.Fab")
			(effects
				(font
					(size 1.27 1.27)
				)
				(justify mirror)
			)
		)
		(duplicate_pad_numbers_are_jumpers no)
		(fp_line
			(start -0.299974 0.150114)
			(end 0.299974 0.150114)
			(stroke
				(width 0.1)
				(type default)
			)
			(layer "B.Fab")
		)
		(fp_line
			(start 0.299974 0.150114)
			(end 0.299974 -0.150114)
			(stroke
				(width 0.1)
				(type default)
			)
			(layer "B.Fab")
		)
		(fp_line
			(start -0.299974 -0.150114)
			(end -0.299974 0.150114)
			(stroke
				(width 0.1)
				(type default)
			)
			(layer "B.Fab")
		)
		(fp_line
			(start 0.299974 -0.150114)
			(end -0.299974 -0.150114)
			(stroke
				(width 0.1)
				(type default)
			)
			(layer "B.Fab")
		)
		(pad "1" smd rect
			(at 0.2667 0 90)
			(size 0.3048 0.381)
			(layers "B.Cu" "B.Mask" "B.Paste")
			(net "P1V8_CPU0_RT3_1A")
		)
		(pad "2" smd rect
			(at -0.2667 0 90)
			(size 0.3048 0.381)
			(layers "B.Cu" "B.Mask" "B.Paste")
			(net "GND")
		)
	)
	(footprint ""
		(layer "B.Cu")
		(at 319.322958 -203.917296 -90)
		(property "Reference" "R388"
			(at 0 0 90)
			(layer "B.SilkS")
			(hide yes)
			(effects
				(font
					(size 1.27 1.27)
				)
				(justify mirror)
			)
		)
		(property "Value" ""
			(at 0 0 90)
			(layer "B.Fab")
			(effects
				(font
					(size 1.27 1.27)
				)
				(justify mirror)
			)
		)
		(duplicate_pad_numbers_are_jumpers no)
		(fp_line
			(start -0.7874 0.4064)
			(end 0.7874 0.4064)
			(stroke
				(width 0.1524)
				(type default)
			)
			(layer "B.SilkS")
		)
		(fp_line
			(start 0.7874 0.4064)
			(end 0.7874 -0.4064)
			(stroke
				(width 0.1524)
				(type default)
			)
			(layer "B.SilkS")
		)
		(fp_line
			(start -0.7874 -0.4064)
			(end -0.7874 0.4064)
			(stroke
				(width 0.1524)
				(type default)
			)
			(layer "B.SilkS")
		)
		(fp_line
			(start 0.7874 -0.4064)
			(end -0.7874 -0.4064)
			(stroke
				(width 0.1524)
				(type default)
			)
			(layer "B.SilkS")
		)
		(fp_line
			(start -0.67945 0.3048)
			(end -0.120396 0.3048)
			(stroke
				(width 0.1)
				(type default)
			)
			(layer "B.Fab")
		)
		(fp_line
			(start -0.120396 0.3048)
			(end -0.120396 0.2794)
			(stroke
				(width 0.1)
				(type default)
			)
			(layer "B.Fab")
		)
		(fp_line
			(start 0.12065 0.3048)
			(end 0.67945 0.3048)
			(stroke
				(width 0.1)
				(type default)
			)
			(layer "B.Fab")
		)
		(fp_line
			(start 0.67945 0.3048)
			(end 0.67945 -0.305054)
			(stroke
				(width 0.1)
				(type default)
			)
			(layer "B.Fab")
		)
		(fp_line
			(start -0.120396 0.2794)
			(end 0.12065 0.2794)
			(stroke
				(width 0.1)
				(type default)
			)
			(layer "B.Fab")
		)
		(fp_line
			(start 0.12065 0.2794)
			(end 0.12065 0.3048)
			(stroke
				(width 0.1)
				(type default)
			)
			(layer "B.Fab")
		)
		(fp_line
			(start -0.12065 -0.2794)
			(end -0.12065 -0.3048)
			(stroke
				(width 0.1)
				(type default)
			)
			(layer "B.Fab")
		)
		(fp_line
			(start 0.12065 -0.2794)
			(end -0.12065 -0.2794)
			(stroke
				(width 0.1)
				(type default)
			)
			(layer "B.Fab")
		)
		(fp_line
			(start -0.67945 -0.3048)
			(end -0.67945 0.3048)
			(stroke
				(width 0.1)
				(type default)
			)
			(layer "B.Fab")
		)
		(fp_line
			(start -0.12065 -0.3048)
			(end -0.67945 -0.3048)
			(stroke
				(width 0.1)
				(type default)
			)
			(layer "B.Fab")
		)
		(fp_line
			(start 0.12065 -0.305054)
			(end 0.12065 -0.2794)
			(stroke
				(width 0.1)
				(type default)
			)
			(layer "B.Fab")
		)
		(fp_line
			(start 0.67945 -0.305054)
			(end 0.12065 -0.305054)
			(stroke
				(width 0.1)
				(type default)
			)
			(layer "B.Fab")
		)
		(pad "1" smd circle
			(at 0.40005 0 90)
			(size 0 0)
			(layers "B.Cu" "B.Mask" "B.Paste")
			(net "P3V3_AUX")
		)
		(pad "2" smd circle
			(at -0.40005 0 90)
			(size 0 0)
			(layers "B.Cu" "B.Mask" "B.Paste")
			(net "CPU0_CORETYPE1")
		)
	)
)
